# BASEBOARD_FAB2 (Tioga Pass) — schematic netlist excerpt (pin names and nets, part order shuffled) for the footprints in the layout excerpt that follows; sources: Cadence DE-HDL packaged netlist, KiCad conversion of Wiwynn_Tioga_Pass_MB.brd

R4D19  RES  27.4 1% CHIP  pkg 0402  page 103 : A = CLK_100M_CPU1_RC_REFCLK0_R_DP ; B = CLK_100M_CPU1_RC_REFCLK0_DP
R25W33  120R2F-GP  1%  pkg RCL_GP  page 151 : \1\ = BMC_M_CAS_N ; \2\ = P1V2_AUX_BMC

(kicad_pcb
	(version 20260206)
	(generator "pcbnew")
	(generator_version "10.0")
	(general
		(thickness 1.6)
		(legacy_teardrops no)
	)
	(paper "A4")
	(title_block
		(title "Wiwynn_Tioga_Pass_MB.brd")
		(comment 1 "Tioga Pass / footprints 50-51 of 4770")
	)
	(layers
		(0 "F.Cu" signal "TOP")
		(4 "In1.Cu" signal "L2GND")
		(6 "In2.Cu" signal "L3")
		(8 "In3.Cu" signal "L4GND")
		(10 "In4.Cu" signal "L5")
		(12 "In5.Cu" signal "L6GND")
		(14 "In6.Cu" signal "L7VCC")
		(16 "In7.Cu" signal "L8VCC")
		(18 "In8.Cu" signal "L9GND")
		(20 "In9.Cu" signal "L10")
		(22 "In10.Cu" signal "L11GND")
		(24 "In11.Cu" signal "L12")
		(26 "In12.Cu" signal "L13GND")
		(2 "B.Cu" signal "BOTTOM")
		(9 "F.Adhes" user "F.Adhesive")
		(11 "B.Adhes" user "B.Adhesive")
		(13 "F.Paste" user "Package Geometry/Pastemask Top")
		(15 "B.Paste" user "Package Geometry/Pastemask Bottom")
		(5 "F.SilkS" user "Ref Des/Silkscreen Top")
		(7 "B.SilkS" user "Ref Des/Silkscreen Bottom")
		(1 "F.Mask" user "Board Geometry/Soldermask Top")
		(3 "B.Mask" user "Board Geometry/Soldermask Bottom")
		(17 "Dwgs.User" user "User.Drawings")
		(19 "Cmts.User" user "User.Comments")
		(21 "Eco1.User" user "User.Eco1")
		(23 "Eco2.User" user "User.Eco2")
		(25 "Edge.Cuts" user "Board Geometry/Outline")
		(27 "Margin" user)
		(31 "F.CrtYd" user "Package Geometry/Place Bound Top")
		(29 "B.CrtYd" user "Package Geometry/Place Bound Bottom")
		(35 "F.Fab" user "Ref Des/Assembly Top")
		(33 "B.Fab" user "Ref Des/Assembly Bottom")
	)
	(footprint ""
		(layer "F.Cu")
		(at 439.976006 -43.568874 180)
		(property "Reference" "R25W33"
			(at 0 0 180)
			(layer "F.SilkS")
			(hide yes)
			(effects
				(font
					(size 1.27 1.27)
				)
			)
		)
		(property "Value" "*"
			(at 0.064008 -4.108196 180)
			(unlocked yes)
			(layer "F.Fab")
			(hide yes)
			(effects
				(font
					(size 1.27 1.016)
					(thickness 0.1524)
				)
			)
		)
		(property "Device Type" "120R2F-GP_RCL_GP-120R2F-GP,64.A"
			(at 0.064008 -5.632196 180)
			(unlocked yes)
			(layer "F.Fab")
			(hide yes)
			(effects
				(font
					(size 1.27 1.016)
					(thickness 0.1524)
				)
			)
		)
		(duplicate_pad_numbers_are_jumpers no)
		(fp_line
			(start 0.508 -0.9398)
			(end -0.508 -0.9398)
			(stroke
				(width 0.1524)
				(type default)
			)
			(layer "F.SilkS")
		)
		(fp_line
			(start -0.508 -0.9398)
			(end -0.508 0.9398)
			(stroke
				(width 0.1524)
				(type default)
			)
			(layer "F.SilkS")
		)
		(fp_rect
			(start -0.508 0.9398)
			(end 0.508 -0.9398)
			(stroke
				(width 0)
				(type default)
			)
			(fill no)
			(layer "F.CrtYd")
		)
		(fp_rect
			(start -0.508 0.9398)
			(end 0.508 -0.9398)
			(stroke
				(width 0)
				(type default)
			)
			(fill no)
			(layer "F.Fab")
		)
		(pad "1" smd custom
			(at 0 -0.4445 180)
			(size 0.1397 0.1397)
			(layers "F.Cu" "F.Mask" "F.Paste")
			(net "BMC_M_CAS_N")
			(options
				(clearance outline)
				(anchor circle)
			)
			(primitives
				(gr_poly
					(pts
						(arc
							(start -0.1778 -0.2794)
							(mid -0.249642 -0.249642)
							(end -0.2794 -0.1778)
						)
						(arc
							(start -0.2794 0.1778)
							(mid -0.249642 0.249642)
							(end -0.1778 0.2794)
						)
						(arc
							(start 0.1778 0.2794)
							(mid 0.249642 0.249642)
							(end 0.2794 0.1778)
						)
						(arc
							(start 0.2794 -0.1778)
							(mid 0.249642 -0.249642)
							(end 0.1778 -0.2794)
						)
					)
					(width 0)
					(fill yes)
				)
			)
		)
		(pad "2" smd custom
			(at 0 0.4445 180)
			(size 0.1397 0.1397)
			(layers "F.Cu" "F.Mask" "F.Paste")
			(net "P1V2_AUX_BMC")
			(options
				(clearance outline)
				(anchor circle)
			)
			(primitives
				(gr_poly
					(pts
						(arc
							(start -0.1778 -0.2794)
							(mid -0.249642 -0.249642)
							(end -0.2794 -0.1778)
						)
						(arc
							(start -0.2794 0.1778)
							(mid -0.249642 0.249642)
							(end -0.1778 0.2794)
						)
						(arc
							(start 0.1778 0.2794)
							(mid 0.249642 0.249642)
							(end 0.2794 0.1778)
						)
						(arc
							(start 0.2794 -0.1778)
							(mid 0.249642 -0.249642)
							(end 0.1778 -0.2794)
						)
					)
					(width 0)
					(fill yes)
				)
			)
		)
	)
	(footprint ""
		(layer "F.Cu")
		(at 163.576 -80.518 -90)
		(property "Reference" "R4D19"
			(at 0 0 270)
			(layer "F.SilkS")
			(hide yes)
			(effects
				(font
					(size 1.27 1.27)
				)
			)
		)
		(property "Value" ""
			(at 0 0 270)
			(layer "F.Fab")
			(effects
				(font
					(size 1.27 1.27)
				)
			)
		)
		(duplicate_pad_numbers_are_jumpers no)
		(fp_poly
			(pts
				(xy -0.2794 -0.1016) (xy 0.2794 -0.1016) (xy 0.2794 0.9906) (xy -0.2794 0.9906)
			)
			(stroke
				(width 0)
				(type default)
			)
			(fill no)
			(layer "F.CrtYd")
		)
		(fp_line
			(start -0.2794 0.9906)
			(end 0.2794 0.9906)
			(stroke
				(width 0.1)
				(type default)
			)
			(layer "F.Fab")
		)
		(fp_line
			(start 0.2794 0.9906)
			(end 0.2794 -0.1016)
			(stroke
				(width 0.1)
				(type default)
			)
			(layer "F.Fab")
		)
		(fp_line
			(start -0.2794 -0.1016)
			(end -0.2794 0.9906)
			(stroke
				(width 0.1)
				(type default)
			)
			(layer "F.Fab")
		)
		(fp_line
			(start 0.2794 -0.1016)
			(end -0.2794 -0.1016)
			(stroke
				(width 0.1)
				(type default)
			)
			(layer "F.Fab")
		)
		(pad "1" smd rect
			(at 0 0 270)
			(size 0.508 0.508)
			(layers "F.Cu" "F.Mask" "F.Paste")
			(net "CLK_100M_CPU1_RC_REFCLK0_R_DP")
		)
		(pad "2" smd rect
			(at 0 0.889 270)
			(size 0.508 0.508)
			(layers "F.Cu" "F.Mask" "F.Paste")
			(net "CLK_100M_CPU1_RC_REFCLK0_DP")
		)
		(zone
			(layer "F.Cu")
			(hatch none 0.5)
			(connect_pads
				(clearance 0)
			)
			(min_thickness 0.25)
			(keepout
				(tracks not_allowed)
				(vias allowed)
				(pads allowed)
				(copperpour not_allowed)
				(footprints allowed)
			)
			(placement
				(enabled no)
				(sheetname "")
			)
			(fill
				(thermal_gap 0.5)
				(thermal_bridge_width 0.5)
				(island_removal_mode 0)
			)
			(polygon
				(pts
					(xy 162.941 -80.772) (xy 162.941 -80.264) (xy 163.322 -80.264) (xy 163.322 -80.772)
				)
			)
		)
		(zone
			(layer "F.Cu")
			(hatch none 0.5)
			(connect_pads
				(clearance 0)
			)
			(min_thickness 0.25)
			(keepout
				(tracks allowed)
				(vias not_allowed)
				(pads allowed)
				(copperpour not_allowed)
				(footprints allowed)
			)
			(placement
				(enabled no)
				(sheetname "")
			)
			(fill
				(thermal_gap 0.5)
				(thermal_bridge_width 0.5)
				(island_removal_mode 0)
			)
			(polygon
				(pts
					(xy 163.322 -80.772) (xy 163.322 -80.264) (xy 162.941 -80.264) (xy 162.941 -80.772)
				)
			)
		)
	)
)
